(kicad_pcb
	(version 20260206)
	(generator "pcbnew")
	(generator_version "10.0")
	(general
		(thickness 1.6)
		(legacy_teardrops no)
	)
	(paper "A4")
	(title_block
		(title "baseboard — 13948-1b.1110WZS1818.brd")
		(comment 1 "Honey Badger (Wiwynn) / footprints 197-203 of 2523")
	)
	(layers
		(0 "F.Cu" signal "TOP")
		(4 "In1.Cu" signal "L2GND")
		(6 "In2.Cu" signal "L3")
		(8 "In3.Cu" signal "L4VCC")
		(10 "In4.Cu" signal "L5VCC")
		(12 "In5.Cu" signal "L6")
		(14 "In6.Cu" signal "L7GND")
		(2 "B.Cu" signal "BOTTOM")
		(9 "F.Adhes" user "F.Adhesive")
		(11 "B.Adhes" user "B.Adhesive")
		(13 "F.Paste" user "Package Geometry/Pastemask Top")
		(15 "B.Paste" user "Package Geometry/Pastemask Bottom")
		(5 "F.SilkS" user "Ref Des/Silkscreen Top")
		(7 "B.SilkS" user "Ref Des/Silkscreen Bottom")
		(1 "F.Mask" user "Board Geometry/Soldermask Top")
		(3 "B.Mask" user "Board Geometry/Soldermask Bottom")
		(17 "Dwgs.User" user "User.Drawings")
		(19 "Cmts.User" user "User.Comments")
		(21 "Eco1.User" user "User.Eco1")
		(23 "Eco2.User" user "User.Eco2")
		(25 "Edge.Cuts" user "Board Geometry/Outline")
		(27 "Margin" user)
		(31 "F.CrtYd" user "Package Geometry/Place Bound Top")
		(29 "B.CrtYd" user "Package Geometry/Place Bound Bottom")
		(35 "F.Fab" user "Ref Des/Assembly Top")
		(33 "B.Fab" user "Ref Des/Assembly Bottom")
	)
	(footprint ""
		(layer "F.Cu")
		(at 337.684872 -165.553136 180)
		(property "Reference" "U28"
			(at 0 0 180)
			(layer "F.SilkS")
			(hide yes)
			(effects
				(font
					(size 1.27 1.27)
				)
			)
		)
		(property "Value" "TS5A23157DGSR-GP"
			(at 0 -11.1252 180)
			(unlocked yes)
			(layer "F.Fab")
			(hide yes)
			(effects
				(font
					(size 1.016 1.016)
					(thickness 0.1524)
				)
			)
		)
		(property "Device Type" "MSOP10H44"
			(at 0 -12.6492 180)
			(unlocked yes)
			(layer "F.Fab")
			(hide yes)
			(effects
				(font
					(size 1.016 1.016)
					(thickness 0.1524)
				)
			)
		)
		(duplicate_pad_numbers_are_jumpers no)
		(fp_line
			(start 1.143 1.016)
			(end -2.0066 1.016)
			(stroke
				(width 0.1524)
				(type default)
			)
			(layer "F.SilkS")
		)
		(fp_line
			(start 1.143 -1.016)
			(end 1.143 1.016)
			(stroke
				(width 0.1524)
				(type default)
			)
			(layer "F.SilkS")
		)
		(fp_line
			(start -1.5748 0)
			(end -1.9558 0.381)
			(stroke
				(width 0.1524)
				(type default)
			)
			(layer "F.SilkS")
		)
		(fp_line
			(start -1.5748 0)
			(end -1.9558 -0.381)
			(stroke
				(width 0.1524)
				(type default)
			)
			(layer "F.SilkS")
		)
		(fp_line
			(start -1.8288 1.016)
			(end -1.8288 3.048)
			(stroke
				(width 0.508)
				(type default)
			)
			(layer "F.SilkS")
		)
		(fp_line
			(start -2.0066 1.016)
			(end -2.0066 -1.016)
			(stroke
				(width 0.1524)
				(type default)
			)
			(layer "F.SilkS")
		)
		(fp_line
			(start -2.0066 -1.016)
			(end 1.143 -1.016)
			(stroke
				(width 0.1524)
				(type default)
			)
			(layer "F.SilkS")
		)
		(fp_poly
			(pts
				(xy -2.0828 3.3401) (xy 2.0828 3.3401) (xy 2.0828 -3.3401) (xy -2.0828 -3.3401)
			)
			(stroke
				(width 0)
				(type default)
			)
			(fill no)
			(layer "F.CrtYd")
		)
		(fp_poly
			(pts
				(xy -2.0828 3.3401) (xy 2.0828 3.3401) (xy 2.0828 -3.3401) (xy -2.0828 -3.3401)
			)
			(stroke
				(width 0)
				(type default)
			)
			(fill no)
			(layer "F.Fab")
		)
		(pad "1" smd rect
			(at -0.99949 2.0701 180)
			(size 0.3048 1.524)
			(layers "F.Cu" "F.Mask" "F.Paste")
			(net "BMC_UART_SWITCH_R")
		)
		(pad "2" smd rect
			(at -0.50038 2.0701 180)
			(size 0.3048 1.524)
			(layers "F.Cu" "F.Mask" "F.Paste")
			(net "UART2_TX")
		)
		(pad "3" smd rect
			(at 0 2.0701 180)
			(size 0.3048 1.524)
			(layers "F.Cu" "F.Mask" "F.Paste")
			(net "GND")
		)
		(pad "4" smd rect
			(at 0.50038 2.0701 180)
			(size 0.3048 1.524)
			(layers "F.Cu" "F.Mask" "F.Paste")
			(net "UART2_RX")
		)
		(pad "5" smd rect
			(at 0.99949 2.0701 180)
			(size 0.3048 1.524)
			(layers "F.Cu" "F.Mask" "F.Paste")
			(net "BMC_UART_SWITCH_R")
		)
		(pad "6" smd rect
			(at 0.99949 -2.0701 180)
			(size 0.3048 1.524)
			(layers "F.Cu" "F.Mask" "F.Paste")
			(net "DEBUG_CARD_RX")
		)
		(pad "7" smd rect
			(at 0.50038 -2.0701 180)
			(size 0.3048 1.524)
			(layers "F.Cu" "F.Mask" "F.Paste")
			(net "UART1_RX")
		)
		(pad "8" smd rect
			(at 0 -2.0701 180)
			(size 0.3048 1.524)
			(layers "F.Cu" "F.Mask" "F.Paste")
			(net "P3V3_STBY")
		)
		(pad "9" smd rect
			(at -0.50038 -2.0701 180)
			(size 0.3048 1.524)
			(layers "F.Cu" "F.Mask" "F.Paste")
			(net "UART1_TX")
		)
		(pad "10" smd rect
			(at -0.99949 -2.0701 180)
			(size 0.3048 1.524)
			(layers "F.Cu" "F.Mask" "F.Paste")
			(net "DEBUG_CARD_TX")
		)
	)
	(footprint ""
		(layer "F.Cu")
		(at 314.4774 -217.3224)
		(property "Reference" "R574"
			(at 0 0 0)
			(layer "F.SilkS")
			(hide yes)
			(effects
				(font
					(size 1.27 1.27)
				)
			)
		)
		(property "Value" "0R2J-2-GP"
			(at 0.064008 -3.993896 0)
			(unlocked yes)
			(layer "F.Fab")
			(hide yes)
			(effects
				(font
					(size 1.016 1.016)
					(thickness 0.1524)
				)
			)
		)
		(property "Device Type" "R402H16"
			(at 0.064008 -5.517896 0)
			(unlocked yes)
			(layer "F.Fab")
			(hide yes)
			(effects
				(font
					(size 1.016 1.016)
					(thickness 0.1524)
				)
			)
		)
		(duplicate_pad_numbers_are_jumpers no)
		(fp_line
			(start -0.508 -0.9398)
			(end -0.508 0.9398)
			(stroke
				(width 0.1524)
				(type default)
			)
			(layer "F.SilkS")
		)
		(fp_line
			(start 0.508 -0.9398)
			(end -0.508 -0.9398)
			(stroke
				(width 0.1524)
				(type default)
			)
			(layer "F.SilkS")
		)
		(fp_rect
			(start -0.508 0.9398)
			(end 0.508 -0.9398)
			(stroke
				(width 0)
				(type default)
			)
			(fill no)
			(layer "F.CrtYd")
		)
		(fp_rect
			(start -0.508 0.9398)
			(end 0.508 -0.9398)
			(stroke
				(width 0)
				(type default)
			)
			(fill no)
			(layer "F.Fab")
		)
		(pad "1" smd custom
			(at 0 -0.4445)
			(size 0.1397 0.1397)
			(layers "F.Cu" "F.Mask" "F.Paste")
			(net "JTAG_EXP_TDO")
			(options
				(clearance outline)
				(anchor circle)
			)
			(primitives
				(gr_poly
					(pts
						(arc
							(start -0.1778 -0.2794)
							(mid -0.249642 -0.249642)
							(end -0.2794 -0.1778)
						)
						(arc
							(start -0.2794 0.1778)
							(mid -0.249642 0.249642)
							(end -0.1778 0.2794)
						)
						(arc
							(start 0.1778 0.2794)
							(mid 0.249642 0.249642)
							(end 0.2794 0.1778)
						)
						(arc
							(start 0.2794 -0.1778)
							(mid 0.249642 -0.249642)
							(end 0.1778 -0.2794)
						)
					)
					(width 0)
					(fill yes)
				)
			)
		)
		(pad "2" smd custom
			(at 0 0.4445)
			(size 0.1397 0.1397)
			(layers "F.Cu" "F.Mask" "F.Paste")
			(net "JTAG_EXP_R_TDO")
			(options
				(clearance outline)
				(anchor circle)
			)
			(primitives
				(gr_poly
					(pts
						(arc
							(start -0.1778 -0.2794)
							(mid -0.249642 -0.249642)
							(end -0.2794 -0.1778)
						)
						(arc
							(start -0.2794 0.1778)
							(mid -0.249642 0.249642)
							(end -0.1778 0.2794)
						)
						(arc
							(start 0.1778 0.2794)
							(mid 0.249642 0.249642)
							(end 0.2794 0.1778)
						)
						(arc
							(start 0.2794 -0.1778)
							(mid 0.249642 -0.249642)
							(end 0.1778 -0.2794)
						)
					)
					(width 0)
					(fill yes)
				)
			)
		)
	)
	(footprint ""
		(layer "F.Cu")
		(at 304.419 -219.837 180)
		(property "Reference" "U42"
			(at 0 0 180)
			(layer "F.SilkS")
			(hide yes)
			(effects
				(font
					(size 1.27 1.27)
				)
			)
		)
		(property "Value" "SN74LVC1G00DC-1GP"
			(at -2.3368 -8.6868 180)
			(unlocked yes)
			(layer "F.Fab")
			(hide yes)
			(effects
				(font
					(size 1.016 1.016)
					(thickness 0.1524)
				)
			)
		)
		(property "Device Type" "SC70-5H44"
			(at -2.3114 -10.414 180)
			(unlocked yes)
			(layer "F.Fab")
			(hide yes)
			(effects
				(font
					(size 1.016 1.016)
					(thickness 0.1524)
				)
			)
		)
		(duplicate_pad_numbers_are_jumpers no)
		(fp_line
			(start 1.3843 -1.8034)
			(end 1.3843 -1.1176)
			(stroke
				(width 0.3302)
				(type default)
			)
			(layer "F.SilkS")
		)
		(fp_line
			(start 1.27 1.7018)
			(end -1.27 1.7018)
			(stroke
				(width 0.1524)
				(type default)
			)
			(layer "F.SilkS")
		)
		(fp_line
			(start 1.27 -1.7018)
			(end 1.27 1.7018)
			(stroke
				(width 0.1524)
				(type default)
			)
			(layer "F.SilkS")
		)
		(fp_line
			(start 0.6604 -1.8034)
			(end 1.3843 -1.8034)
			(stroke
				(width 0.3302)
				(type default)
			)
			(layer "F.SilkS")
		)
		(fp_line
			(start -1.27 1.7018)
			(end -1.27 -1.7018)
			(stroke
				(width 0.1524)
				(type default)
			)
			(layer "F.SilkS")
		)
		(fp_line
			(start -1.27 -1.7018)
			(end 1.27 -1.7018)
			(stroke
				(width 0.1524)
				(type default)
			)
			(layer "F.SilkS")
		)
		(fp_rect
			(start -1.524 1.9558)
			(end 1.524 -1.9558)
			(stroke
				(width 0)
				(type default)
			)
			(fill no)
			(layer "F.CrtYd")
		)
		(fp_poly
			(pts
				(xy -1.524 -1.9558) (xy 1.524 -1.9558) (xy 1.524 1.9558) (xy -1.524 1.9558)
			)
			(stroke
				(width 0)
				(type default)
			)
			(fill no)
			(layer "F.Fab")
		)
		(pad "1" smd rect
			(at 0.65024 -0.8255 180)
			(size 0.4064 1.2192)
			(layers "F.Cu" "F.Mask" "F.Paste")
			(net "PMU_PLTRST_N")
		)
		(pad "2" smd rect
			(at 0 -0.8255 180)
			(size 0.4064 1.2192)
			(layers "F.Cu" "F.Mask" "F.Paste")
			(net "BMC_DEBUG_OE_1_N")
		)
		(pad "3" smd rect
			(at -0.65024 -0.8255 180)
			(size 0.4064 1.2192)
			(layers "F.Cu" "F.Mask" "F.Paste")
			(net "GND")
		)
		(pad "4" smd rect
			(at -0.65024 0.8255 180)
			(size 0.4064 1.2192)
			(layers "F.Cu" "F.Mask" "F.Paste")
			(net "DEBUG_OE_1_N")
		)
		(pad "5" smd rect
			(at 0.65024 0.8255 180)
			(size 0.4064 1.2192)
			(layers "F.Cu" "F.Mask" "F.Paste")
			(net "P3V3_STBY")
		)
	)
	(footprint ""
		(layer "F.Cu")
		(at 173.99 -93.726 90)
		(property "Reference" "PTC4"
			(at 0 0 90)
			(layer "F.SilkS")
			(hide yes)
			(effects
				(font
					(size 1.27 1.27)
				)
			)
		)
		(property "Value" "SE470UF2VDM-GP"
			(at 0 -9.6012 90)
			(unlocked yes)
			(layer "F.Fab")
			(hide yes)
			(effects
				(font
					(size 1.016 1.016)
					(thickness 0.1524)
				)
			)
		)
		(property "Device Type" "CT7343H83"
			(at 0 -11.1252 90)
			(unlocked yes)
			(layer "F.Fab")
			(hide yes)
			(effects
				(font
					(size 1.016 1.016)
					(thickness 0.1524)
				)
			)
		)
		(duplicate_pad_numbers_are_jumpers no)
		(fp_line
			(start 2.286 -4.8768)
			(end -2.286 -4.8768)
			(stroke
				(width 0.1524)
				(type default)
			)
			(layer "F.SilkS")
		)
		(fp_line
			(start -2.286 -4.8768)
			(end -2.286 -2.032)
			(stroke
				(width 0.1524)
				(type default)
			)
			(layer "F.SilkS")
		)
		(fp_line
			(start 2.1082 -4.699)
			(end -2.1082 -4.699)
			(stroke
				(width 0.508)
				(type default)
			)
			(layer "F.SilkS")
		)
		(fp_line
			(start 2.286 -2.032)
			(end 2.286 -4.8768)
			(stroke
				(width 0.1524)
				(type default)
			)
			(layer "F.SilkS")
		)
		(fp_line
			(start 2.286 2.032)
			(end 2.286 4.8768)
			(stroke
				(width 0.1524)
				(type default)
			)
			(layer "F.SilkS")
		)
		(fp_line
			(start 2.286 4.8768)
			(end -2.286 4.8768)
			(stroke
				(width 0.1524)
				(type default)
			)
			(layer "F.SilkS")
		)
		(fp_line
			(start -2.286 4.8768)
			(end -2.286 2.032)
			(stroke
				(width 0.1524)
				(type default)
			)
			(layer "F.SilkS")
		)
		(fp_rect
			(start -2.1463 3.6449)
			(end 2.1463 -3.6449)
			(stroke
				(width 0)
				(type default)
			)
			(fill no)
			(layer "F.CrtYd")
		)
		(fp_poly
			(pts
				(xy -2.54 4.953) (xy -2.54 4.2926) (xy -3.81 4.2926) (xy -3.81 -4.2926) (xy -2.54 -4.2926) (xy -2.54 -4.953)
				(xy 2.54 -4.953) (xy 2.54 -4.2926) (xy 3.81 -4.2926) (xy 3.81 -1.6256) (xy 2.1463 -1.6256) (xy 2.1463 -3.6449)
				(xy -2.1463 -3.6449) (xy -2.1463 3.6449) (xy 2.1463 3.6449) (xy 2.1463 -1.6129) (xy 3.81 -1.6129)
				(xy 3.81 4.2926) (xy 2.54 4.2926) (xy 2.54 4.953)
			)
			(stroke
				(width 0)
				(type default)
			)
			(fill no)
			(layer "F.CrtYd")
		)
		(fp_rect
			(start 2.54 4.2926)
			(end 3.81 -4.2926)
			(stroke
				(width 0)
				(type default)
			)
			(fill no)
			(layer "F.Fab")
		)
		(fp_rect
			(start -3.81 4.2926)
			(end -2.54 -4.2926)
			(stroke
				(width 0)
				(type default)
			)
			(fill no)
			(layer "F.Fab")
		)
		(fp_rect
			(start -2.54 4.953)
			(end 2.54 -4.953)
			(stroke
				(width 0)
				(type default)
			)
			(fill no)
			(layer "F.Fab")
		)
		(pad "1" smd rect
			(at 0 -3.1496 90)
			(size 2.413 2.286)
			(layers "F.Cu" "F.Mask" "F.Paste")
			(net "P0V9_E")
		)
		(pad "2" smd rect
			(at 0 3.1496 90)
			(size 2.413 2.286)
			(layers "F.Cu" "F.Mask" "F.Paste")
			(net "GND")
		)
		(zone
			(layer "F.Cu")
			(hatch none 0.5)
			(connect_pads
				(clearance 0)
			)
			(min_thickness 0.25)
			(keepout
				(tracks allowed)
				(vias not_allowed)
				(pads allowed)
				(copperpour not_allowed)
				(footprints allowed)
			)
			(placement
				(enabled no)
				(sheetname "")
			)
			(fill
				(thermal_gap 0.5)
				(thermal_bridge_width 0.5)
				(island_removal_mode 0)
			)
			(polygon
				(pts
					(xy 172.3009 -95.2373) (xy 169.3926 -95.2373) (xy 169.3926 -92.2147) (xy 172.2882 -92.2147) (xy 172.6184 -92.2147)
					(xy 172.6184 -95.2373)
				)
			)
		)
		(zone
			(layer "F.Cu")
			(hatch none 0.5)
			(connect_pads
				(clearance 0)
			)
			(min_thickness 0.25)
			(keepout
				(tracks allowed)
				(vias not_allowed)
				(pads allowed)
				(copperpour not_allowed)
				(footprints allowed)
			)
			(placement
				(enabled no)
				(sheetname "")
			)
			(fill
				(thermal_gap 0.5)
				(thermal_bridge_width 0.5)
				(island_removal_mode 0)
			)
			(polygon
				(pts
					(xy 178.5874 -92.2147) (xy 178.5874 -95.2373) (xy 175.6918 -95.2373) (xy 175.3616 -95.2373) (xy 175.3616 -92.2147)
					(xy 175.6918 -92.2147)
				)
			)
		)
	)
	(footprint ""
		(layer "F.Cu")
		(at 103.13797 -78.105)
		(property "Reference" "STP149"
			(at 0 0 0)
			(layer "F.SilkS")
			(hide yes)
			(effects
				(font
					(size 1.27 1.27)
				)
			)
		)
		(property "Value" "TPAD28"
			(at 0.0127 -1.8034 0)
			(unlocked yes)
			(layer "F.Fab")
			(hide yes)
			(effects
				(font
					(size 1.016 1.016)
					(thickness 0.1524)
				)
			)
		)
		(property "Device Type" "TPAD28"
			(at 0.0127 -3.3274 0)
			(unlocked yes)
			(layer "F.Fab")
			(hide yes)
			(effects
				(font
					(size 1.016 1.016)
					(thickness 0.1524)
				)
			)
		)
		(duplicate_pad_numbers_are_jumpers no)
		(fp_poly
			(pts
				(arc
					(start 0.3556 0)
					(mid -0.3556 0)
					(end 0.3556 0)
				)
			)
			(stroke
				(width 0)
				(type default)
			)
			(fill no)
			(layer "F.CrtYd")
		)
		(fp_poly
			(pts
				(arc
					(start 0.6096 0)
					(mid -0.6096 0)
					(end 0.6096 0)
				)
			)
			(stroke
				(width 0)
				(type default)
			)
			(fill no)
			(layer "F.Fab")
		)
		(pad "1" smd circle
			(at 0 0)
			(size 0.7112 0.7112)
			(layers "F.Cu" "F.Mask" "F.Paste")
			(net "JTAG_EXP_TDI")
		)
	)
	(footprint ""
		(layer "F.Cu")
		(at 166.243 -117.475 -90)
		(property "Reference" "PSP2"
			(at 0 0 270)
			(layer "F.SilkS")
			(hide yes)
			(effects
				(font
					(size 1.27 1.27)
				)
			)
		)
		(property "Value" "COPPER-CLOSE-GP-U"
			(at 0.0762 -2.8702 270)
			(unlocked yes)
			(layer "F.Fab")
			(hide yes)
			(effects
				(font
					(size 1.016 1.016)
					(thickness 0.1524)
				)
			)
		)
		(property "Device Type" "CON2C-U"
			(at 0.0762 -4.3942 270)
			(unlocked yes)
			(layer "F.Fab")
			(hide yes)
			(effects
				(font
					(size 1.016 1.016)
					(thickness 0.1524)
				)
			)
		)
		(duplicate_pad_numbers_are_jumpers no)
		(fp_rect
			(start -0.9398 0.9652)
			(end 0.9398 -0.9652)
			(stroke
				(width 0)
				(type default)
			)
			(fill no)
			(layer "F.CrtYd")
		)
		(fp_rect
			(start -0.9398 0.9652)
			(end 0.9398 -0.9652)
			(stroke
				(width 0)
				(type default)
			)
			(fill no)
			(layer "F.Fab")
		)
		(pad "1" smd custom
			(at 0 -0.5334 270)
			(size 0.17145 0.17145)
			(layers "F.Cu" "F.Mask" "F.Paste")
			(net "GND")
			(options
				(clearance outline)
				(anchor circle)
			)
			(primitives
				(gr_poly
					(pts
						(xy -0.127 0.3429) (xy -0.127 0.1651) (xy -0.635 -0.3429) (xy 0.635 -0.3429) (xy 0.127 0.1651)
						(xy 0.127 0.3429)
					)
					(width 0)
					(fill yes)
				)
			)
		)
		(pad "2" smd custom
			(at 0 0.5334 270)
			(size 0.17145 0.17145)
			(layers "F.Cu" "F.Mask" "F.Paste")
			(net "AGND_P0V9_E")
			(options
				(clearance outline)
				(anchor circle)
			)
			(primitives
				(gr_poly
					(pts
						(xy -0.635 0.3429) (xy -0.127 -0.1651) (xy -0.127 -0.3429) (xy 0.127 -0.3429) (xy 0.127 -0.1651)
						(xy 0.635 0.3429)
					)
					(width 0)
					(fill yes)
				)
			)
		)
	)
	(footprint ""
		(layer "F.Cu")
		(at 84.963 -31.75 180)
		(property "Reference" "SC965"
			(at 0 0 180)
			(layer "F.SilkS")
			(hide yes)
			(effects
				(font
					(size 1.27 1.27)
				)
			)
		)
		(property "Value" "SCD1U6D3V1KX-GP"
			(at -2.8321 -1.7399 180)
			(unlocked yes)
			(layer "F.Fab")
			(hide yes)
			(effects
				(font
					(size 1.016 1.016)
					(thickness 0.1524)
				)
			)
		)
		(property "Device Type" "C0201H13"
			(at -2.8321 -3.2639 180)
			(unlocked yes)
			(layer "F.Fab")
			(hide yes)
			(effects
				(font
					(size 1.016 1.016)
					(thickness 0.1524)
				)
			)
		)
		(duplicate_pad_numbers_are_jumpers no)
		(fp_rect
			(start -0.2794 0.6477)
			(end 0.2794 -0.6477)
			(stroke
				(width 0)
				(type default)
			)
			(fill no)
			(layer "F.CrtYd")
		)
		(fp_rect
			(start -0.2794 0.6477)
			(end 0.2794 -0.6477)
			(stroke
				(width 0)
				(type default)
			)
			(fill no)
			(layer "F.Fab")
		)
		(pad "1" smd custom
			(at 0 -0.2794 180)
			(size 0.0762 0.0762)
			(layers "F.Cu" "F.Mask" "F.Paste")
			(net "SAS0_AVDD")
			(options
				(clearance outline)
				(anchor circle)
			)
			(primitives
				(gr_poly
					(pts
						(arc
							(start 0.1524 -0.127)
							(mid 0.137521 -0.162921)
							(end 0.1016 -0.1778)
						)
						(arc
							(start -0.1016 -0.1778)
							(mid -0.137521 -0.162921)
							(end -0.1524 -0.127)
						)
						(arc
							(start -0.1524 0.127)
							(mid -0.137521 0.162921)
							(end -0.1016 0.1778)
						)
						(arc
							(start 0.1016 0.1778)
							(mid 0.137521 0.162921)
							(end 0.1524 0.127)
						)
					)
					(width 0)
					(fill yes)
				)
			)
		)
		(pad "2" smd custom
			(at 0 0.2794 180)
			(size 0.0762 0.0762)
			(layers "F.Cu" "F.Mask" "F.Paste")
			(net "GND")
			(options
				(clearance outline)
				(anchor circle)
			)
			(primitives
				(gr_poly
					(pts
						(arc
							(start 0.1524 -0.127)
							(mid 0.137521 -0.162921)
							(end 0.1016 -0.1778)
						)
						(arc
							(start -0.1016 -0.1778)
							(mid -0.137521 -0.162921)
							(end -0.1524 -0.127)
						)
						(arc
							(start -0.1524 0.127)
							(mid -0.137521 0.162921)
							(end -0.1016 0.1778)
						)
						(arc
							(start 0.1016 0.1778)
							(mid 0.137521 0.162921)
							(end 0.1524 0.127)
						)
					)
					(width 0)
					(fill yes)
				)
			)
		)
	)
)
